# GrandTeton_FIO_BOM_20230829.xlsx — main_source (bom)
| Description | Manuf_name | Manuf_PN | Quantity | Part Reference |
| CAP CHIP 10U 16V(+-20%,X6S,0603) | MURATA ERIE N.A. INC TAIWAN BRANCH Okayama Murata | GRM188C81C106M | 2 | C1,C3 |
| CAP CHIP 0.1U 25V(+-10%,X7R,0402) | MURATA ERIE N.A. INC TAIWAN BRANCH Okayama Murata | GRM155R71E104K | 1 | C2 |
| CAP CHIP 0.1U 16V(10%.X7R.0402) | MURATA ERIE N.A. INC TAIWAN BRANCH Okayama Murata Mfg.Co..Ltd. Wakura Murata Mfg | WBM155R71C104K | 4 | C5,C7,C11 |
| CAP CHIP 100P 50V(+-5%.NPO.0402) | "RTECH TECHNOLOGY CO..LTD.(Compostar)" | CC0402N101J3SST-S | 1 | C6 |
| CAP CHIP 22UF 16V(+-20%,X6S,0805)MUR | MURATA ERIE N.A. INC TAIWAN BRANCH Okayama Murata | GRM21BC81C226M | 6 | C9,C10,C12,C14,C15,C16 |
| CAP CHIP 2.2UF 10V(+-10%,X6S,0402) | MURATA ERIE N.A. INC TAIWAN BRANCH Okayama Murata | GRM155C81A225K | 3 | C4,C8,C13 |
| LED DIP(2P)YELLOW(LTL-R42FSFADH213T) | LITE-ON CORP.(LITE-ON IT CORPORATION) | LTL-R42FSFADH213T | 1 | D2 |
| LED DIP(2P)BLUE (LTLR42FTBGAJH213T) | LITE-ON CORP.(LITE-ON IT CORPORATION) | LTLR42FTBGAJH213T | 1 | D3 |
| CONN SMD HOUSING 38P 2R FR(P0.6,H6.6) | SPEED TECH CORP. | PSL060-3847-T11-1H | 1 | J1 |
| CONN DIP USB3.0 9P 2R FR(P2.0,H13.8) | LOTES(CHIA TSE TERMINAL INDUSTRYLOTES SUZHOU CO.,LTD | AUSB0043-P033A | 1 | J2 |
| TRANS MOSFET DMN53D0LDW(50V,0.36A,0.31W) | DIODES TAIWAN CO.,LTD. | DMN53D0LDW-7 | 1 | Q1 |
| RES CHIP 0 1/16W +-5%(0402)EF | WALSIN TECHNOLOGY CORPORATION | WR04X000PTR | 8 | R13,R14,R15,R51,R52,R65,R67,R68 |
| RES CHIP 100K 1/16W +-1%(0402)EF | WALSIN TECHNOLOGY CORPORATION | WR04X1003FTR | 3 | R6,R8,R12 |
| RES CHIP 360 1/10W +-1%(0603)EF | WALSIN TECHNOLOGY CORPORATION | WR06X3600FTR | 2 | R7,R11 |
| RES CHIP 4.75K 1/16W +-1%(0402)EF | WALSIN TECHNOLOGY CORPORATION | WR04X4751FTR | 1 | R10 |
| RES CHIP 33.2 1/16W +-1%(0402)EF | WALSIN TECHNOLOGY CORPORATION | WR04X33R2FTR | 4 | R16,R17,R48,R49 |
| RES CHIP 10K 1/16W +-1%(0402)EF | WALSIN TECHNOLOGY CORPORATION | WR04X1002FTR | 4 | R19,R20,R21,R22 |
| RES CHIP 10K 1/16W +-5%(0402)EF | WALSIN TECHNOLOGY CORPORATION | WR04X103 JTR | 7 | R29,R40,R41,R61,R62,R64 |
| RES CHIP 100K 1/16W +-5%(0402)EF | WALSIN TECHNOLOGY CORPORATION | WR04X104 JTR | 5 | R28,R37,R38,R39,R50 |
| RES CHIP 33 1/16W +-5%(0402)EF | WALSIN TECHNOLOGY CORPORATION | WR04X330 JTR | 2 | R35,R36 |
| RES CHIP 18.2K 1/16W +-1%(0402)EF | TA-I TECHNOLOGY CO.,LTD. | RM04FTW1822 | 1 | R42 |
| RES CHIP 4.7K 1/16W +-5%(0402)EF | WALSIN TECHNOLOGY CORPORATION | WR04X472 JTR | 3 | R44,R45,R58 |
| RES CHIP 33 1/16W +-1%(0402)EF | WALSIN TECHNOLOGY CORPORATION | WR04X33R0FTR | 2 | R59,R60 |
| TRANMOS 2N7002KW SOT323(60V, 115MA,0.2W) | PAN JIT INTERNATIONAL INC. | 2N7002KW | 2 | U3,U4 |
| IC OTHER(24P)PCA9539RPW(TSSOP) | NXP semiconductors | PCA9539RPW | 1 | U5 |
| IC OTHER (8P) LM75BD(SO8) | NXP semiconductors | LM75BD | 1 | U6 |
| IC OTHER(6P)NCP380HSNAJAAT1G(TSOP-6) | ON SEMICONDUCTOR | NCP380HSNAJAAT1G | 1 | U7 |
| IC OTHER (4P) PRTR5V0U2X (SOT143B) | NXP semiconductors | PRTR5V0U2X | 3 | U8,U10,U11 |
| IC EEPROM(8P) M24C64-WMN6TP(8K*8,SO8) | SGS-THOMSON(STMicroelectronics) | M24C64-WMN6TP | 1 | U9 |
| RES CHIP 4.7K 1/16W +-1%(0402)EF | WALSIN TECHNOLOGY CORPORATION | WR04X4701FTR | 2 | R30,R31 |
| RES CHIP 22 1/16W +-1%(0402)EF | WALSIN TECHNOLOGY CORPORATION | WR04X22R0FTR | 1 | R66 |
